(kicad_pcb
	(version 20260206)
	(generator "pcbnew")
	(generator_version "10.0")
	(general
		(thickness 1.6)
		(legacy_teardrops no)
	)
	(paper "A4")
	(title_block
		(title "04192023_DAF0TMB3IC0_F0TG_MB_C_brd_V02_OCP.brd")
		(comment 1 "Grand Teton / footprints 1019-1025 of 8354")
	)
	(layers
		(0 "F.Cu" signal "TOP")
		(4 "In1.Cu" signal "GND")
		(6 "In2.Cu" signal "IN1")
		(8 "In3.Cu" signal "GND1")
		(10 "In4.Cu" signal "IN2")
		(12 "In5.Cu" signal "GND2")
		(14 "In6.Cu" signal "IN3")
		(16 "In7.Cu" signal "GND3")
		(18 "In8.Cu" signal "VCC")
		(20 "In9.Cu" signal "VCC1")
		(22 "In10.Cu" signal "GND4")
		(24 "In11.Cu" signal "IN4")
		(26 "In12.Cu" signal "GND5")
		(28 "In13.Cu" signal "IN5")
		(30 "In14.Cu" signal "GND6")
		(32 "In15.Cu" signal "IN6")
		(34 "In16.Cu" signal "GND7")
		(2 "B.Cu" signal "BOTTOM")
		(9 "F.Adhes" user "F.Adhesive")
		(11 "B.Adhes" user "B.Adhesive")
		(13 "F.Paste" user "Package Geometry/Pastemask Top")
		(15 "B.Paste" user "Package Geometry/Pastemask Bottom")
		(5 "F.SilkS" user "Ref Des/Silkscreen Top")
		(7 "B.SilkS" user "Ref Des/Silkscreen Bottom")
		(1 "F.Mask" user "Board Geometry/Soldermask Top")
		(3 "B.Mask" user "Board Geometry/Soldermask Bottom")
		(17 "Dwgs.User" user "User.Drawings")
		(19 "Cmts.User" user "User.Comments")
		(21 "Eco1.User" user "User.Eco1")
		(23 "Eco2.User" user "User.Eco2")
		(25 "Edge.Cuts" user "Board Geometry/Outline")
		(27 "Margin" user)
		(31 "F.CrtYd" user "Package Geometry/Place Bound Top")
		(29 "B.CrtYd" user "Package Geometry/Place Bound Bottom")
		(35 "F.Fab" user "Ref Des/Assembly Top")
		(33 "B.Fab" user "Ref Des/Assembly Bottom")
	)
	(footprint ""
		(layer "F.Cu")
		(at 43.4721 -171.831)
		(property "Reference" "R989"
			(at 0 0 0)
			(layer "F.SilkS")
			(hide yes)
			(effects
				(font
					(size 1.27 1.27)
				)
			)
		)
		(property "Value" ""
			(at 0 0 0)
			(layer "F.Fab")
			(effects
				(font
					(size 1.27 1.27)
				)
			)
		)
		(duplicate_pad_numbers_are_jumpers no)
		(fp_line
			(start -0.7874 -0.4064)
			(end 0.7874 -0.4064)
			(stroke
				(width 0.1524)
				(type default)
			)
			(layer "F.SilkS")
		)
		(fp_line
			(start -0.7874 0.4064)
			(end -0.7874 -0.4064)
			(stroke
				(width 0.1524)
				(type default)
			)
			(layer "F.SilkS")
		)
		(fp_line
			(start 0.7874 -0.4064)
			(end 0.7874 0.4064)
			(stroke
				(width 0.1524)
				(type default)
			)
			(layer "F.SilkS")
		)
		(fp_line
			(start 0.7874 0.4064)
			(end -0.7874 0.4064)
			(stroke
				(width 0.1524)
				(type default)
			)
			(layer "F.SilkS")
		)
		(fp_line
			(start -0.67945 -0.305054)
			(end -0.12065 -0.305054)
			(stroke
				(width 0.1)
				(type default)
			)
			(layer "F.Fab")
		)
		(fp_line
			(start -0.67945 0.3048)
			(end -0.67945 -0.305054)
			(stroke
				(width 0.1)
				(type default)
			)
			(layer "F.Fab")
		)
		(fp_line
			(start -0.12065 -0.305054)
			(end -0.12065 -0.2794)
			(stroke
				(width 0.1)
				(type default)
			)
			(layer "F.Fab")
		)
		(fp_line
			(start -0.12065 -0.2794)
			(end 0.12065 -0.2794)
			(stroke
				(width 0.1)
				(type default)
			)
			(layer "F.Fab")
		)
		(fp_line
			(start -0.12065 0.2794)
			(end -0.12065 0.3048)
			(stroke
				(width 0.1)
				(type default)
			)
			(layer "F.Fab")
		)
		(fp_line
			(start -0.12065 0.3048)
			(end -0.67945 0.3048)
			(stroke
				(width 0.1)
				(type default)
			)
			(layer "F.Fab")
		)
		(fp_line
			(start 0.120396 0.2794)
			(end -0.12065 0.2794)
			(stroke
				(width 0.1)
				(type default)
			)
			(layer "F.Fab")
		)
		(fp_line
			(start 0.120396 0.3048)
			(end 0.120396 0.2794)
			(stroke
				(width 0.1)
				(type default)
			)
			(layer "F.Fab")
		)
		(fp_line
			(start 0.12065 -0.3048)
			(end 0.67945 -0.3048)
			(stroke
				(width 0.1)
				(type default)
			)
			(layer "F.Fab")
		)
		(fp_line
			(start 0.12065 -0.2794)
			(end 0.12065 -0.3048)
			(stroke
				(width 0.1)
				(type default)
			)
			(layer "F.Fab")
		)
		(fp_line
			(start 0.67945 -0.3048)
			(end 0.67945 0.3048)
			(stroke
				(width 0.1)
				(type default)
			)
			(layer "F.Fab")
		)
		(fp_line
			(start 0.67945 0.3048)
			(end 0.120396 0.3048)
			(stroke
				(width 0.1)
				(type default)
			)
			(layer "F.Fab")
		)
		(pad "1" smd rect
			(at -0.40005 0 180)
			(size 0.4572 0.508)
			(layers "F.Cu" "F.Mask" "F.Paste")
			(net "I3C_0_SPD_DDRAF_CPU1_R_SDA")
		)
		(pad "2" smd rect
			(at 0.40005 0 180)
			(size 0.4572 0.508)
			(layers "F.Cu" "F.Mask" "F.Paste")
			(net "I3C_SPD_DDRAF_CPU1_BYPASS_SDA")
		)
	)
	(footprint ""
		(layer "F.Cu")
		(at 49.866296 -344.986864 90)
		(property "Reference" "PR488"
			(at 0 0 90)
			(layer "F.SilkS")
			(hide yes)
			(effects
				(font
					(size 1.27 1.27)
				)
			)
		)
		(property "Value" ""
			(at 0 0 90)
			(layer "F.Fab")
			(effects
				(font
					(size 1.27 1.27)
				)
			)
		)
		(duplicate_pad_numbers_are_jumpers no)
		(fp_line
			(start 0.7874 -0.4064)
			(end 0.7874 0.4064)
			(stroke
				(width 0.1524)
				(type default)
			)
			(layer "F.SilkS")
		)
		(fp_line
			(start -0.7874 -0.4064)
			(end 0.7874 -0.4064)
			(stroke
				(width 0.1524)
				(type default)
			)
			(layer "F.SilkS")
		)
		(fp_line
			(start 0.7874 0.4064)
			(end -0.7874 0.4064)
			(stroke
				(width 0.1524)
				(type default)
			)
			(layer "F.SilkS")
		)
		(fp_line
			(start -0.7874 0.4064)
			(end -0.7874 -0.4064)
			(stroke
				(width 0.1524)
				(type default)
			)
			(layer "F.SilkS")
		)
		(fp_line
			(start -0.12065 -0.305054)
			(end -0.12065 -0.2794)
			(stroke
				(width 0.1)
				(type default)
			)
			(layer "F.Fab")
		)
		(fp_line
			(start -0.67945 -0.305054)
			(end -0.12065 -0.305054)
			(stroke
				(width 0.1)
				(type default)
			)
			(layer "F.Fab")
		)
		(fp_line
			(start 0.67945 -0.3048)
			(end 0.67945 0.3048)
			(stroke
				(width 0.1)
				(type default)
			)
			(layer "F.Fab")
		)
		(fp_line
			(start 0.12065 -0.3048)
			(end 0.67945 -0.3048)
			(stroke
				(width 0.1)
				(type default)
			)
			(layer "F.Fab")
		)
		(fp_line
			(start 0.12065 -0.2794)
			(end 0.12065 -0.3048)
			(stroke
				(width 0.1)
				(type default)
			)
			(layer "F.Fab")
		)
		(fp_line
			(start -0.12065 -0.2794)
			(end 0.12065 -0.2794)
			(stroke
				(width 0.1)
				(type default)
			)
			(layer "F.Fab")
		)
		(fp_line
			(start 0.120396 0.2794)
			(end -0.12065 0.2794)
			(stroke
				(width 0.1)
				(type default)
			)
			(layer "F.Fab")
		)
		(fp_line
			(start -0.12065 0.2794)
			(end -0.12065 0.3048)
			(stroke
				(width 0.1)
				(type default)
			)
			(layer "F.Fab")
		)
		(fp_line
			(start 0.67945 0.3048)
			(end 0.120396 0.3048)
			(stroke
				(width 0.1)
				(type default)
			)
			(layer "F.Fab")
		)
		(fp_line
			(start 0.120396 0.3048)
			(end 0.120396 0.2794)
			(stroke
				(width 0.1)
				(type default)
			)
			(layer "F.Fab")
		)
		(fp_line
			(start -0.12065 0.3048)
			(end -0.67945 0.3048)
			(stroke
				(width 0.1)
				(type default)
			)
			(layer "F.Fab")
		)
		(fp_line
			(start -0.67945 0.3048)
			(end -0.67945 -0.305054)
			(stroke
				(width 0.1)
				(type default)
			)
			(layer "F.Fab")
		)
		(pad "1" smd circle
			(at -0.40005 0 90)
			(size 0 0)
			(layers "F.Cu" "F.Mask" "F.Paste")
			(net "SW_PVDDIO_P1_SW1_RC")
		)
		(pad "2" smd circle
			(at 0.40005 0 90)
			(size 0 0)
			(layers "F.Cu" "F.Mask" "F.Paste")
			(net "GND")
		)
	)
	(footprint ""
		(layer "F.Cu")
		(at 47.861982 -397.751808)
		(property "Reference" "C240"
			(at 0 0 0)
			(layer "F.SilkS")
			(hide yes)
			(effects
				(font
					(size 1.27 1.27)
				)
			)
		)
		(property "Value" ""
			(at 0 0 0)
			(layer "F.Fab")
			(effects
				(font
					(size 1.27 1.27)
				)
			)
		)
		(duplicate_pad_numbers_are_jumpers no)
		(fp_line
			(start -1.524 -0.762)
			(end 1.524 -0.762)
			(stroke
				(width 0.1524)
				(type default)
			)
			(layer "F.SilkS")
		)
		(fp_line
			(start -1.524 0.762)
			(end -1.524 -0.762)
			(stroke
				(width 0.1524)
				(type default)
			)
			(layer "F.SilkS")
		)
		(fp_line
			(start 1.524 -0.762)
			(end 1.524 0.762)
			(stroke
				(width 0.1524)
				(type default)
			)
			(layer "F.SilkS")
		)
		(fp_line
			(start 1.524 0.762)
			(end -1.524 0.762)
			(stroke
				(width 0.1524)
				(type default)
			)
			(layer "F.SilkS")
		)
		(fp_line
			(start -1.1049 -0.724916)
			(end -1.1049 0.724916)
			(stroke
				(width 0.1)
				(type default)
			)
			(layer "F.Fab")
		)
		(fp_line
			(start -1.1049 0.724916)
			(end 1.1049 0.724916)
			(stroke
				(width 0.1)
				(type default)
			)
			(layer "F.Fab")
		)
		(fp_line
			(start 1.1049 -0.724916)
			(end -1.1049 -0.724916)
			(stroke
				(width 0.1)
				(type default)
			)
			(layer "F.Fab")
		)
		(fp_line
			(start 1.1049 0.724916)
			(end 1.1049 -0.724916)
			(stroke
				(width 0.1)
				(type default)
			)
			(layer "F.Fab")
		)
		(pad "1" smd rect
			(at -0.889 0 180)
			(size 1.016 1.27)
			(layers "F.Cu" "F.Mask" "F.Paste")
			(net "P0V9_CPU1_RT0_2A")
		)
		(pad "2" smd rect
			(at 0.889 0 180)
			(size 1.016 1.27)
			(layers "F.Cu" "F.Mask" "F.Paste")
			(net "GND")
		)
	)
	(footprint ""
		(layer "F.Cu")
		(at 41.73601 -438.531)
		(property "Reference" "R3468"
			(at 0 0 0)
			(layer "F.SilkS")
			(hide yes)
			(effects
				(font
					(size 1.27 1.27)
				)
			)
		)
		(property "Value" ""
			(at 0 0 0)
			(layer "F.Fab")
			(effects
				(font
					(size 1.27 1.27)
				)
			)
		)
		(duplicate_pad_numbers_are_jumpers no)
		(fp_line
			(start -0.7874 -0.4064)
			(end 0.7874 -0.4064)
			(stroke
				(width 0.1524)
				(type default)
			)
			(layer "F.SilkS")
		)
		(fp_line
			(start -0.7874 0.4064)
			(end -0.7874 -0.4064)
			(stroke
				(width 0.1524)
				(type default)
			)
			(layer "F.SilkS")
		)
		(fp_line
			(start 0.7874 -0.4064)
			(end 0.7874 0.4064)
			(stroke
				(width 0.1524)
				(type default)
			)
			(layer "F.SilkS")
		)
		(fp_line
			(start 0.7874 0.4064)
			(end -0.7874 0.4064)
			(stroke
				(width 0.1524)
				(type default)
			)
			(layer "F.SilkS")
		)
		(fp_line
			(start -0.67945 -0.305054)
			(end -0.12065 -0.305054)
			(stroke
				(width 0.1)
				(type default)
			)
			(layer "F.Fab")
		)
		(fp_line
			(start -0.67945 0.3048)
			(end -0.67945 -0.305054)
			(stroke
				(width 0.1)
				(type default)
			)
			(layer "F.Fab")
		)
		(fp_line
			(start -0.12065 -0.305054)
			(end -0.12065 -0.2794)
			(stroke
				(width 0.1)
				(type default)
			)
			(layer "F.Fab")
		)
		(fp_line
			(start -0.12065 -0.2794)
			(end 0.12065 -0.2794)
			(stroke
				(width 0.1)
				(type default)
			)
			(layer "F.Fab")
		)
		(fp_line
			(start -0.12065 0.2794)
			(end -0.12065 0.3048)
			(stroke
				(width 0.1)
				(type default)
			)
			(layer "F.Fab")
		)
		(fp_line
			(start -0.12065 0.3048)
			(end -0.67945 0.3048)
			(stroke
				(width 0.1)
				(type default)
			)
			(layer "F.Fab")
		)
		(fp_line
			(start 0.120396 0.2794)
			(end -0.12065 0.2794)
			(stroke
				(width 0.1)
				(type default)
			)
			(layer "F.Fab")
		)
		(fp_line
			(start 0.120396 0.3048)
			(end 0.120396 0.2794)
			(stroke
				(width 0.1)
				(type default)
			)
			(layer "F.Fab")
		)
		(fp_line
			(start 0.12065 -0.3048)
			(end 0.67945 -0.3048)
			(stroke
				(width 0.1)
				(type default)
			)
			(layer "F.Fab")
		)
		(fp_line
			(start 0.12065 -0.2794)
			(end 0.12065 -0.3048)
			(stroke
				(width 0.1)
				(type default)
			)
			(layer "F.Fab")
		)
		(fp_line
			(start 0.67945 -0.3048)
			(end 0.67945 0.3048)
			(stroke
				(width 0.1)
				(type default)
			)
			(layer "F.Fab")
		)
		(fp_line
			(start 0.67945 0.3048)
			(end 0.120396 0.3048)
			(stroke
				(width 0.1)
				(type default)
			)
			(layer "F.Fab")
		)
		(pad "1" smd circle
			(at -0.40005 0)
			(size 0 0)
			(layers "F.Cu" "F.Mask" "F.Paste")
			(net "RST_PERST_1_SWB_BUF_R_N")
		)
		(pad "2" smd circle
			(at 0.40005 0)
			(size 0 0)
			(layers "F.Cu" "F.Mask" "F.Paste")
			(net "RST_PERST_1_SWB_BUF_N")
		)
	)
	(footprint ""
		(layer "F.Cu")
		(at 261.76605 -380.66853)
		(property "Reference" "PR2529"
			(at 0 0 0)
			(layer "F.SilkS")
			(hide yes)
			(effects
				(font
					(size 1.27 1.27)
				)
			)
		)
		(property "Value" ""
			(at 0 0 0)
			(layer "F.Fab")
			(effects
				(font
					(size 1.27 1.27)
				)
			)
		)
		(duplicate_pad_numbers_are_jumpers no)
		(fp_line
			(start -0.7874 -0.4064)
			(end 0.7874 -0.4064)
			(stroke
				(width 0.1524)
				(type default)
			)
			(layer "F.SilkS")
		)
		(fp_line
			(start -0.7874 0.4064)
			(end -0.7874 -0.4064)
			(stroke
				(width 0.1524)
				(type default)
			)
			(layer "F.SilkS")
		)
		(fp_line
			(start 0.7874 -0.4064)
			(end 0.7874 0.4064)
			(stroke
				(width 0.1524)
				(type default)
			)
			(layer "F.SilkS")
		)
		(fp_line
			(start 0.7874 0.4064)
			(end -0.7874 0.4064)
			(stroke
				(width 0.1524)
				(type default)
			)
			(layer "F.SilkS")
		)
		(fp_line
			(start -0.67945 -0.305054)
			(end -0.12065 -0.305054)
			(stroke
				(width 0.1)
				(type default)
			)
			(layer "F.Fab")
		)
		(fp_line
			(start -0.67945 0.3048)
			(end -0.67945 -0.305054)
			(stroke
				(width 0.1)
				(type default)
			)
			(layer "F.Fab")
		)
		(fp_line
			(start -0.12065 -0.305054)
			(end -0.12065 -0.2794)
			(stroke
				(width 0.1)
				(type default)
			)
			(layer "F.Fab")
		)
		(fp_line
			(start -0.12065 -0.2794)
			(end 0.12065 -0.2794)
			(stroke
				(width 0.1)
				(type default)
			)
			(layer "F.Fab")
		)
		(fp_line
			(start -0.12065 0.2794)
			(end -0.12065 0.3048)
			(stroke
				(width 0.1)
				(type default)
			)
			(layer "F.Fab")
		)
		(fp_line
			(start -0.12065 0.3048)
			(end -0.67945 0.3048)
			(stroke
				(width 0.1)
				(type default)
			)
			(layer "F.Fab")
		)
		(fp_line
			(start 0.120396 0.2794)
			(end -0.12065 0.2794)
			(stroke
				(width 0.1)
				(type default)
			)
			(layer "F.Fab")
		)
		(fp_line
			(start 0.120396 0.3048)
			(end 0.120396 0.2794)
			(stroke
				(width 0.1)
				(type default)
			)
			(layer "F.Fab")
		)
		(fp_line
			(start 0.12065 -0.3048)
			(end 0.67945 -0.3048)
			(stroke
				(width 0.1)
				(type default)
			)
			(layer "F.Fab")
		)
		(fp_line
			(start 0.12065 -0.2794)
			(end 0.12065 -0.3048)
			(stroke
				(width 0.1)
				(type default)
			)
			(layer "F.Fab")
		)
		(fp_line
			(start 0.67945 -0.3048)
			(end 0.67945 0.3048)
			(stroke
				(width 0.1)
				(type default)
			)
			(layer "F.Fab")
		)
		(fp_line
			(start 0.67945 0.3048)
			(end 0.120396 0.3048)
			(stroke
				(width 0.1)
				(type default)
			)
			(layer "F.Fab")
		)
		(pad "1" smd circle
			(at -0.40005 0)
			(size 0 0)
			(layers "F.Cu" "F.Mask" "F.Paste")
			(net "P12V_HSC_GATE_G2")
		)
		(pad "2" smd circle
			(at 0.40005 0)
			(size 0 0)
			(layers "F.Cu" "F.Mask" "F.Paste")
			(net "P12V_HSC_GATE2")
		)
	)
	(footprint ""
		(layer "F.Cu")
		(at 122.002296 -375.49963 -90)
		(property "Reference" "C1533"
			(at 0 0 270)
			(layer "F.SilkS")
			(hide yes)
			(effects
				(font
					(size 1.27 1.27)
				)
			)
		)
		(property "Value" ""
			(at 0 0 270)
			(layer "F.Fab")
			(effects
				(font
					(size 1.27 1.27)
				)
			)
		)
		(duplicate_pad_numbers_are_jumpers no)
		(fp_line
			(start -0.299974 0.150114)
			(end -0.299974 -0.150114)
			(stroke
				(width 0.1)
				(type default)
			)
			(layer "F.Fab")
		)
		(fp_line
			(start 0.299974 0.150114)
			(end -0.299974 0.150114)
			(stroke
				(width 0.1)
				(type default)
			)
			(layer "F.Fab")
		)
		(fp_line
			(start -0.299974 -0.150114)
			(end 0.299974 -0.150114)
			(stroke
				(width 0.1)
				(type default)
			)
			(layer "F.Fab")
		)
		(fp_line
			(start 0.299974 -0.150114)
			(end 0.299974 0.150114)
			(stroke
				(width 0.1)
				(type default)
			)
			(layer "F.Fab")
		)
		(pad "1" smd rect
			(at -0.2667 0 270)
			(size 0.3048 0.381)
			(layers "F.Cu" "F.Mask" "F.Paste")
			(net "P5E_CPU1_P3_TX_C_DP<7>")
		)
		(pad "2" smd rect
			(at 0.2667 0 270)
			(size 0.3048 0.381)
			(layers "F.Cu" "F.Mask" "F.Paste")
			(net "P5E_CPU1_P3_TX_DP<7>")
		)
	)
	(footprint ""
		(layer "F.Cu")
		(at 306.420266 -431.256186)
		(property "Reference" "R4142"
			(at 0 0 0)
			(layer "F.SilkS")
			(hide yes)
			(effects
				(font
					(size 1.27 1.27)
				)
			)
		)
		(property "Value" ""
			(at 0 0 0)
			(layer "F.Fab")
			(effects
				(font
					(size 1.27 1.27)
				)
			)
		)
		(duplicate_pad_numbers_are_jumpers no)
		(fp_line
			(start -0.7874 -0.4064)
			(end 0.7874 -0.4064)
			(stroke
				(width 0.1524)
				(type default)
			)
			(layer "F.SilkS")
		)
		(fp_line
			(start -0.7874 0.4064)
			(end -0.7874 -0.4064)
			(stroke
				(width 0.1524)
				(type default)
			)
			(layer "F.SilkS")
		)
		(fp_line
			(start 0.7874 -0.4064)
			(end 0.7874 0.4064)
			(stroke
				(width 0.1524)
				(type default)
			)
			(layer "F.SilkS")
		)
		(fp_line
			(start 0.7874 0.4064)
			(end -0.7874 0.4064)
			(stroke
				(width 0.1524)
				(type default)
			)
			(layer "F.SilkS")
		)
		(fp_line
			(start -0.67945 -0.305054)
			(end -0.12065 -0.305054)
			(stroke
				(width 0.1)
				(type default)
			)
			(layer "F.Fab")
		)
		(fp_line
			(start -0.67945 0.3048)
			(end -0.67945 -0.305054)
			(stroke
				(width 0.1)
				(type default)
			)
			(layer "F.Fab")
		)
		(fp_line
			(start -0.12065 -0.305054)
			(end -0.12065 -0.2794)
			(stroke
				(width 0.1)
				(type default)
			)
			(layer "F.Fab")
		)
		(fp_line
			(start -0.12065 -0.2794)
			(end 0.12065 -0.2794)
			(stroke
				(width 0.1)
				(type default)
			)
			(layer "F.Fab")
		)
		(fp_line
			(start -0.12065 0.2794)
			(end -0.12065 0.3048)
			(stroke
				(width 0.1)
				(type default)
			)
			(layer "F.Fab")
		)
		(fp_line
			(start -0.12065 0.3048)
			(end -0.67945 0.3048)
			(stroke
				(width 0.1)
				(type default)
			)
			(layer "F.Fab")
		)
		(fp_line
			(start 0.120396 0.2794)
			(end -0.12065 0.2794)
			(stroke
				(width 0.1)
				(type default)
			)
			(layer "F.Fab")
		)
		(fp_line
			(start 0.120396 0.3048)
			(end 0.120396 0.2794)
			(stroke
				(width 0.1)
				(type default)
			)
			(layer "F.Fab")
		)
		(fp_line
			(start 0.12065 -0.3048)
			(end 0.67945 -0.3048)
			(stroke
				(width 0.1)
				(type default)
			)
			(layer "F.Fab")
		)
		(fp_line
			(start 0.12065 -0.2794)
			(end 0.12065 -0.3048)
			(stroke
				(width 0.1)
				(type default)
			)
			(layer "F.Fab")
		)
		(fp_line
			(start 0.67945 -0.3048)
			(end 0.67945 0.3048)
			(stroke
				(width 0.1)
				(type default)
			)
			(layer "F.Fab")
		)
		(fp_line
			(start 0.67945 0.3048)
			(end 0.120396 0.3048)
			(stroke
				(width 0.1)
				(type default)
			)
			(layer "F.Fab")
		)
		(pad "1" smd circle
			(at -0.40005 0)
			(size 0 0)
			(layers "F.Cu" "F.Mask" "F.Paste")
			(net "P3V3_AUX")
		)
		(pad "2" smd circle
			(at 0.40005 0)
			(size 0 0)
			(layers "F.Cu" "F.Mask" "F.Paste")
			(net "PRSNT_CABLE_GPU_A2_ISO_N")
		)
	)
)
